(kicad_pcb
	(version 20260206)
	(generator "pcbnew")
	(generator_version "10.0")
	(general
		(thickness 1.6)
		(legacy_teardrops no)
	)
	(paper "A4")
	(title_block
		(title "03242023_DA0F0TMBIJ0_F0T_Motherboard_J_brd_V01_OCP.brd")
		(comment 1 "Grand Teton / footprints 2616-2621 of 6105")
	)
	(layers
		(0 "F.Cu" signal "TOP")
		(4 "In1.Cu" signal "GND")
		(6 "In2.Cu" signal "IN1")
		(8 "In3.Cu" signal "GND1")
		(10 "In4.Cu" signal "IN2")
		(12 "In5.Cu" signal "GND2")
		(14 "In6.Cu" signal "IN3")
		(16 "In7.Cu" signal "GND3")
		(18 "In8.Cu" signal "VCC")
		(20 "In9.Cu" signal "VCC1")
		(22 "In10.Cu" signal "GND4")
		(24 "In11.Cu" signal "IN4")
		(26 "In12.Cu" signal "GND5")
		(28 "In13.Cu" signal "IN5")
		(30 "In14.Cu" signal "GND6")
		(32 "In15.Cu" signal "IN6")
		(34 "In16.Cu" signal "GND7")
		(2 "B.Cu" signal "BOTTOM")
		(9 "F.Adhes" user "F.Adhesive")
		(11 "B.Adhes" user "B.Adhesive")
		(13 "F.Paste" user "Package Geometry/Pastemask Top")
		(15 "B.Paste" user "Package Geometry/Pastemask Bottom")
		(5 "F.SilkS" user "Ref Des/Silkscreen Top")
		(7 "B.SilkS" user "Ref Des/Silkscreen Bottom")
		(1 "F.Mask" user "Board Geometry/Soldermask Top")
		(3 "B.Mask" user "Board Geometry/Soldermask Bottom")
		(17 "Dwgs.User" user "User.Drawings")
		(19 "Cmts.User" user "User.Comments")
		(21 "Eco1.User" user "User.Eco1")
		(23 "Eco2.User" user "User.Eco2")
		(25 "Edge.Cuts" user "Board Geometry/Outline")
		(27 "Margin" user)
		(31 "F.CrtYd" user "Package Geometry/Place Bound Top")
		(29 "B.CrtYd" user "Package Geometry/Place Bound Bottom")
		(35 "F.Fab" user "Ref Des/Assembly Top")
		(33 "B.Fab" user "Ref Des/Assembly Bottom")
	)
	(footprint ""
		(layer "F.Cu")
		(at 366.48263 -252.956314 -90)
		(property "Reference" "C1024"
			(at 0 0 270)
			(layer "F.SilkS")
			(hide yes)
			(effects
				(font
					(size 1.27 1.27)
				)
			)
		)
		(property "Value" ""
			(at 0 0 270)
			(layer "F.Fab")
			(effects
				(font
					(size 1.27 1.27)
				)
			)
		)
		(duplicate_pad_numbers_are_jumpers no)
		(fp_line
			(start -0.7874 0.4064)
			(end -0.7874 -0.4064)
			(stroke
				(width 0.1524)
				(type default)
			)
			(layer "F.SilkS")
		)
		(fp_line
			(start 0.7874 0.4064)
			(end -0.7874 0.4064)
			(stroke
				(width 0.1524)
				(type default)
			)
			(layer "F.SilkS")
		)
		(fp_line
			(start -0.7874 -0.4064)
			(end 0.7874 -0.4064)
			(stroke
				(width 0.1524)
				(type default)
			)
			(layer "F.SilkS")
		)
		(fp_line
			(start 0.7874 -0.4064)
			(end 0.7874 0.4064)
			(stroke
				(width 0.1524)
				(type default)
			)
			(layer "F.SilkS")
		)
		(fp_line
			(start -0.67945 0.3048)
			(end -0.67945 -0.305054)
			(stroke
				(width 0.1)
				(type default)
			)
			(layer "F.Fab")
		)
		(fp_line
			(start -0.12065 0.3048)
			(end -0.67945 0.3048)
			(stroke
				(width 0.1)
				(type default)
			)
			(layer "F.Fab")
		)
		(fp_line
			(start 0.120396 0.3048)
			(end 0.120396 0.2794)
			(stroke
				(width 0.1)
				(type default)
			)
			(layer "F.Fab")
		)
		(fp_line
			(start 0.67945 0.3048)
			(end 0.120396 0.3048)
			(stroke
				(width 0.1)
				(type default)
			)
			(layer "F.Fab")
		)
		(fp_line
			(start -0.12065 0.2794)
			(end -0.12065 0.3048)
			(stroke
				(width 0.1)
				(type default)
			)
			(layer "F.Fab")
		)
		(fp_line
			(start 0.120396 0.2794)
			(end -0.12065 0.2794)
			(stroke
				(width 0.1)
				(type default)
			)
			(layer "F.Fab")
		)
		(fp_line
			(start -0.12065 -0.2794)
			(end 0.12065 -0.2794)
			(stroke
				(width 0.1)
				(type default)
			)
			(layer "F.Fab")
		)
		(fp_line
			(start 0.12065 -0.2794)
			(end 0.12065 -0.3048)
			(stroke
				(width 0.1)
				(type default)
			)
			(layer "F.Fab")
		)
		(fp_line
			(start 0.12065 -0.3048)
			(end 0.67945 -0.3048)
			(stroke
				(width 0.1)
				(type default)
			)
			(layer "F.Fab")
		)
		(fp_line
			(start 0.67945 -0.3048)
			(end 0.67945 0.3048)
			(stroke
				(width 0.1)
				(type default)
			)
			(layer "F.Fab")
		)
		(fp_line
			(start -0.67945 -0.305054)
			(end -0.12065 -0.305054)
			(stroke
				(width 0.1)
				(type default)
			)
			(layer "F.Fab")
		)
		(fp_line
			(start -0.12065 -0.305054)
			(end -0.12065 -0.2794)
			(stroke
				(width 0.1)
				(type default)
			)
			(layer "F.Fab")
		)
		(pad "1" smd circle
			(at -0.40005 0 270)
			(size 0 0)
			(layers "F.Cu" "F.Mask" "F.Paste")
			(net "PVCCIN_CPU0")
		)
		(pad "2" smd circle
			(at 0.40005 0 270)
			(size 0 0)
			(layers "F.Cu" "F.Mask" "F.Paste")
			(net "GND")
		)
	)
	(footprint ""
		(layer "F.Cu")
		(at 27.628596 -390.294876)
		(property "Reference" "R3285"
			(at 0 0 0)
			(layer "F.SilkS")
			(hide yes)
			(effects
				(font
					(size 1.27 1.27)
				)
			)
		)
		(property "Value" ""
			(at 0 0 0)
			(layer "F.Fab")
			(effects
				(font
					(size 1.27 1.27)
				)
			)
		)
		(duplicate_pad_numbers_are_jumpers no)
		(fp_line
			(start -0.7874 -0.4064)
			(end 0.7874 -0.4064)
			(stroke
				(width 0.1524)
				(type default)
			)
			(layer "F.SilkS")
		)
		(fp_line
			(start -0.7874 0.4064)
			(end -0.7874 -0.4064)
			(stroke
				(width 0.1524)
				(type default)
			)
			(layer "F.SilkS")
		)
		(fp_line
			(start 0.7874 -0.4064)
			(end 0.7874 0.4064)
			(stroke
				(width 0.1524)
				(type default)
			)
			(layer "F.SilkS")
		)
		(fp_line
			(start 0.7874 0.4064)
			(end -0.7874 0.4064)
			(stroke
				(width 0.1524)
				(type default)
			)
			(layer "F.SilkS")
		)
		(fp_line
			(start -0.67945 -0.305054)
			(end -0.12065 -0.305054)
			(stroke
				(width 0.1)
				(type default)
			)
			(layer "F.Fab")
		)
		(fp_line
			(start -0.67945 0.3048)
			(end -0.67945 -0.305054)
			(stroke
				(width 0.1)
				(type default)
			)
			(layer "F.Fab")
		)
		(fp_line
			(start -0.12065 -0.305054)
			(end -0.12065 -0.2794)
			(stroke
				(width 0.1)
				(type default)
			)
			(layer "F.Fab")
		)
		(fp_line
			(start -0.12065 -0.2794)
			(end 0.12065 -0.2794)
			(stroke
				(width 0.1)
				(type default)
			)
			(layer "F.Fab")
		)
		(fp_line
			(start -0.12065 0.2794)
			(end -0.12065 0.3048)
			(stroke
				(width 0.1)
				(type default)
			)
			(layer "F.Fab")
		)
		(fp_line
			(start -0.12065 0.3048)
			(end -0.67945 0.3048)
			(stroke
				(width 0.1)
				(type default)
			)
			(layer "F.Fab")
		)
		(fp_line
			(start 0.120396 0.2794)
			(end -0.12065 0.2794)
			(stroke
				(width 0.1)
				(type default)
			)
			(layer "F.Fab")
		)
		(fp_line
			(start 0.120396 0.3048)
			(end 0.120396 0.2794)
			(stroke
				(width 0.1)
				(type default)
			)
			(layer "F.Fab")
		)
		(fp_line
			(start 0.12065 -0.3048)
			(end 0.67945 -0.3048)
			(stroke
				(width 0.1)
				(type default)
			)
			(layer "F.Fab")
		)
		(fp_line
			(start 0.12065 -0.2794)
			(end 0.12065 -0.3048)
			(stroke
				(width 0.1)
				(type default)
			)
			(layer "F.Fab")
		)
		(fp_line
			(start 0.67945 -0.3048)
			(end 0.67945 0.3048)
			(stroke
				(width 0.1)
				(type default)
			)
			(layer "F.Fab")
		)
		(fp_line
			(start 0.67945 0.3048)
			(end 0.120396 0.3048)
			(stroke
				(width 0.1)
				(type default)
			)
			(layer "F.Fab")
		)
		(pad "1" smd circle
			(at -0.40005 0)
			(size 0 0)
			(layers "F.Cu" "F.Mask" "F.Paste")
			(net "FM_P2E_SWB")
		)
		(pad "2" smd circle
			(at 0.40005 0)
			(size 0 0)
			(layers "F.Cu" "F.Mask" "F.Paste")
			(net "GND")
		)
	)
	(footprint ""
		(layer "F.Cu")
		(at 302.566324 -34.937446 90)
		(property "Reference" "R1340"
			(at 0 0 90)
			(layer "F.SilkS")
			(hide yes)
			(effects
				(font
					(size 1.27 1.27)
				)
			)
		)
		(property "Value" ""
			(at 0 0 90)
			(layer "F.Fab")
			(effects
				(font
					(size 1.27 1.27)
				)
			)
		)
		(duplicate_pad_numbers_are_jumpers no)
		(fp_line
			(start 0.7874 -0.4064)
			(end 0.7874 0.4064)
			(stroke
				(width 0.1524)
				(type default)
			)
			(layer "F.SilkS")
		)
		(fp_line
			(start -0.7874 -0.4064)
			(end 0.7874 -0.4064)
			(stroke
				(width 0.1524)
				(type default)
			)
			(layer "F.SilkS")
		)
		(fp_line
			(start 0.7874 0.4064)
			(end -0.7874 0.4064)
			(stroke
				(width 0.1524)
				(type default)
			)
			(layer "F.SilkS")
		)
		(fp_line
			(start -0.7874 0.4064)
			(end -0.7874 -0.4064)
			(stroke
				(width 0.1524)
				(type default)
			)
			(layer "F.SilkS")
		)
		(fp_line
			(start -0.12065 -0.305054)
			(end -0.12065 -0.2794)
			(stroke
				(width 0.1)
				(type default)
			)
			(layer "F.Fab")
		)
		(fp_line
			(start -0.67945 -0.305054)
			(end -0.12065 -0.305054)
			(stroke
				(width 0.1)
				(type default)
			)
			(layer "F.Fab")
		)
		(fp_line
			(start 0.67945 -0.3048)
			(end 0.67945 0.3048)
			(stroke
				(width 0.1)
				(type default)
			)
			(layer "F.Fab")
		)
		(fp_line
			(start 0.12065 -0.3048)
			(end 0.67945 -0.3048)
			(stroke
				(width 0.1)
				(type default)
			)
			(layer "F.Fab")
		)
		(fp_line
			(start 0.12065 -0.2794)
			(end 0.12065 -0.3048)
			(stroke
				(width 0.1)
				(type default)
			)
			(layer "F.Fab")
		)
		(fp_line
			(start -0.12065 -0.2794)
			(end 0.12065 -0.2794)
			(stroke
				(width 0.1)
				(type default)
			)
			(layer "F.Fab")
		)
		(fp_line
			(start 0.120396 0.2794)
			(end -0.12065 0.2794)
			(stroke
				(width 0.1)
				(type default)
			)
			(layer "F.Fab")
		)
		(fp_line
			(start -0.12065 0.2794)
			(end -0.12065 0.3048)
			(stroke
				(width 0.1)
				(type default)
			)
			(layer "F.Fab")
		)
		(fp_line
			(start 0.67945 0.3048)
			(end 0.120396 0.3048)
			(stroke
				(width 0.1)
				(type default)
			)
			(layer "F.Fab")
		)
		(fp_line
			(start 0.120396 0.3048)
			(end 0.120396 0.2794)
			(stroke
				(width 0.1)
				(type default)
			)
			(layer "F.Fab")
		)
		(fp_line
			(start -0.12065 0.3048)
			(end -0.67945 0.3048)
			(stroke
				(width 0.1)
				(type default)
			)
			(layer "F.Fab")
		)
		(fp_line
			(start -0.67945 0.3048)
			(end -0.67945 -0.305054)
			(stroke
				(width 0.1)
				(type default)
			)
			(layer "F.Fab")
		)
		(pad "1" smd circle
			(at -0.40005 0 90)
			(size 0 0)
			(layers "F.Cu" "F.Mask" "F.Paste")
			(net "P3V3_RTC_AUX")
		)
		(pad "2" smd circle
			(at 0.40005 0 90)
			(size 0 0)
			(layers "F.Cu" "F.Mask" "F.Paste")
			(net "RST_RTCRST_N")
		)
	)
	(footprint ""
		(layer "F.Cu")
		(at 100.183696 -70.78599)
		(property "Reference" "D79"
			(at -50.276506 50.178462 90)
			(unlocked yes)
			(layer "F.SilkS")
			(effects
				(font
					(size 0.635 0.4064)
					(thickness 0.1524)
				)
				(justify left)
			)
		)
		(property "Value" ""
			(at 0 0 0)
			(layer "F.Fab")
			(effects
				(font
					(size 1.27 1.27)
				)
			)
		)
		(duplicate_pad_numbers_are_jumpers no)
		(fp_line
			(start -0.90678 0.4826)
			(end -0.90678 -0.4699)
			(stroke
				(width 0.1524)
				(type default)
			)
			(layer "F.SilkS")
		)
		(fp_line
			(start -0.89408 -0.4826)
			(end 0.90678 -0.4826)
			(stroke
				(width 0.1524)
				(type default)
			)
			(layer "F.SilkS")
		)
		(fp_line
			(start -0.79248 -0.4826)
			(end 1.03378 -0.4826)
			(stroke
				(width 0.1524)
				(type default)
			)
			(layer "F.SilkS")
		)
		(fp_line
			(start -0.64008 -0.4826)
			(end 1.16078 -0.4826)
			(stroke
				(width 0.1524)
				(type default)
			)
			(layer "F.SilkS")
		)
		(fp_line
			(start 0.90678 -0.4826)
			(end 0.90678 0.4826)
			(stroke
				(width 0.1524)
				(type default)
			)
			(layer "F.SilkS")
		)
		(fp_line
			(start 0.90678 0.4826)
			(end -0.90678 0.4826)
			(stroke
				(width 0.1524)
				(type default)
			)
			(layer "F.SilkS")
		)
		(fp_line
			(start 1.03378 -0.4826)
			(end 1.03378 0.4826)
			(stroke
				(width 0.1524)
				(type default)
			)
			(layer "F.SilkS")
		)
		(fp_line
			(start 1.03378 0.4826)
			(end -0.79248 0.4826)
			(stroke
				(width 0.1524)
				(type default)
			)
			(layer "F.SilkS")
		)
		(fp_line
			(start 1.16078 -0.4826)
			(end 1.16078 0.4826)
			(stroke
				(width 0.1524)
				(type default)
			)
			(layer "F.SilkS")
		)
		(fp_line
			(start 1.16078 0.4826)
			(end -0.64008 0.4826)
			(stroke
				(width 0.1524)
				(type default)
			)
			(layer "F.SilkS")
		)
		(fp_line
			(start -0.499872 -0.249936)
			(end 0.499872 -0.249936)
			(stroke
				(width 0.1)
				(type default)
			)
			(layer "F.Fab")
		)
		(fp_line
			(start -0.499872 0.249936)
			(end -0.499872 -0.249936)
			(stroke
				(width 0.1)
				(type default)
			)
			(layer "F.Fab")
		)
		(fp_line
			(start 0.499872 -0.249936)
			(end 0.499872 0.249936)
			(stroke
				(width 0.1)
				(type default)
			)
			(layer "F.Fab")
		)
		(fp_line
			(start 0.499872 0.249936)
			(end -0.499872 0.249936)
			(stroke
				(width 0.1)
				(type default)
			)
			(layer "F.Fab")
		)
		(pad "A" smd rect
			(at -0.47498 0)
			(size 0.6096 0.7112)
			(layers "F.Cu" "F.Mask" "F.Paste")
			(net "LED_PWRGD_PVCCIN_CPU0")
		)
		(pad "C" smd rect
			(at 0.47498 0)
			(size 0.6096 0.7112)
			(layers "F.Cu" "F.Mask" "F.Paste")
			(net "LED_PWRGD_PVCCIN_CPU0_D")
		)
	)
	(footprint ""
		(layer "F.Cu")
		(at 13.87348 -15.320518 90)
		(property "Reference" "R3178"
			(at 0 0 90)
			(layer "F.SilkS")
			(hide yes)
			(effects
				(font
					(size 1.27 1.27)
				)
			)
		)
		(property "Value" ""
			(at 0 0 90)
			(layer "F.Fab")
			(effects
				(font
					(size 1.27 1.27)
				)
			)
		)
		(duplicate_pad_numbers_are_jumpers no)
		(fp_line
			(start 0.7874 -0.4064)
			(end 0.7874 0.4064)
			(stroke
				(width 0.1524)
				(type default)
			)
			(layer "F.SilkS")
		)
		(fp_line
			(start -0.7874 -0.4064)
			(end 0.7874 -0.4064)
			(stroke
				(width 0.1524)
				(type default)
			)
			(layer "F.SilkS")
		)
		(fp_line
			(start 0.7874 0.4064)
			(end -0.7874 0.4064)
			(stroke
				(width 0.1524)
				(type default)
			)
			(layer "F.SilkS")
		)
		(fp_line
			(start -0.7874 0.4064)
			(end -0.7874 -0.4064)
			(stroke
				(width 0.1524)
				(type default)
			)
			(layer "F.SilkS")
		)
		(fp_line
			(start -0.12065 -0.305054)
			(end -0.12065 -0.2794)
			(stroke
				(width 0.1)
				(type default)
			)
			(layer "F.Fab")
		)
		(fp_line
			(start -0.67945 -0.305054)
			(end -0.12065 -0.305054)
			(stroke
				(width 0.1)
				(type default)
			)
			(layer "F.Fab")
		)
		(fp_line
			(start 0.67945 -0.3048)
			(end 0.67945 0.3048)
			(stroke
				(width 0.1)
				(type default)
			)
			(layer "F.Fab")
		)
		(fp_line
			(start 0.12065 -0.3048)
			(end 0.67945 -0.3048)
			(stroke
				(width 0.1)
				(type default)
			)
			(layer "F.Fab")
		)
		(fp_line
			(start 0.12065 -0.2794)
			(end 0.12065 -0.3048)
			(stroke
				(width 0.1)
				(type default)
			)
			(layer "F.Fab")
		)
		(fp_line
			(start -0.12065 -0.2794)
			(end 0.12065 -0.2794)
			(stroke
				(width 0.1)
				(type default)
			)
			(layer "F.Fab")
		)
		(fp_line
			(start 0.120396 0.2794)
			(end -0.12065 0.2794)
			(stroke
				(width 0.1)
				(type default)
			)
			(layer "F.Fab")
		)
		(fp_line
			(start -0.12065 0.2794)
			(end -0.12065 0.3048)
			(stroke
				(width 0.1)
				(type default)
			)
			(layer "F.Fab")
		)
		(fp_line
			(start 0.67945 0.3048)
			(end 0.120396 0.3048)
			(stroke
				(width 0.1)
				(type default)
			)
			(layer "F.Fab")
		)
		(fp_line
			(start 0.120396 0.3048)
			(end 0.120396 0.2794)
			(stroke
				(width 0.1)
				(type default)
			)
			(layer "F.Fab")
		)
		(fp_line
			(start -0.12065 0.3048)
			(end -0.67945 0.3048)
			(stroke
				(width 0.1)
				(type default)
			)
			(layer "F.Fab")
		)
		(fp_line
			(start -0.67945 0.3048)
			(end -0.67945 -0.305054)
			(stroke
				(width 0.1)
				(type default)
			)
			(layer "F.Fab")
		)
		(pad "1" smd circle
			(at -0.40005 0 90)
			(size 0 0)
			(layers "F.Cu" "F.Mask" "F.Paste")
			(net "USB2_5_R1_DP")
		)
		(pad "2" smd circle
			(at 0.40005 0 90)
			(size 0 0)
			(layers "F.Cu" "F.Mask" "F.Paste")
			(net "USB2_5_DP")
		)
	)
	(footprint ""
		(layer "F.Cu")
		(at 287.83788 -408.75966 -90)
		(property "Reference" "C2459"
			(at 0 0 270)
			(layer "F.SilkS")
			(hide yes)
			(effects
				(font
					(size 1.27 1.27)
				)
			)
		)
		(property "Value" ""
			(at 0 0 270)
			(layer "F.Fab")
			(effects
				(font
					(size 1.27 1.27)
				)
			)
		)
		(duplicate_pad_numbers_are_jumpers no)
		(fp_line
			(start -1.2954 0.5842)
			(end -1.2954 -0.5842)
			(stroke
				(width 0.1524)
				(type default)
			)
			(layer "F.SilkS")
		)
		(fp_line
			(start 1.2954 0.5842)
			(end -1.2954 0.5842)
			(stroke
				(width 0.1524)
				(type default)
			)
			(layer "F.SilkS")
		)
		(fp_line
			(start -1.2954 -0.5842)
			(end 1.2954 -0.5842)
			(stroke
				(width 0.1524)
				(type default)
			)
			(layer "F.SilkS")
		)
		(fp_line
			(start 0 -0.5842)
			(end 0 0.5842)
			(stroke
				(width 0.1524)
				(type default)
			)
			(layer "F.SilkS")
		)
		(fp_line
			(start 1.2954 -0.5842)
			(end 1.2954 0.5842)
			(stroke
				(width 0.1524)
				(type default)
			)
			(layer "F.SilkS")
		)
		(fp_line
			(start -0.8636 0.4572)
			(end -0.8636 0.4064)
			(stroke
				(width 0.1)
				(type default)
			)
			(layer "F.Fab")
		)
		(fp_line
			(start 0.8636 0.4572)
			(end -0.8636 0.4572)
			(stroke
				(width 0.1)
				(type default)
			)
			(layer "F.Fab")
		)
		(fp_line
			(start -1.1938 0.4064)
			(end -1.1938 -0.4064)
			(stroke
				(width 0.1)
				(type default)
			)
			(layer "F.Fab")
		)
		(fp_line
			(start -0.8636 0.4064)
			(end -1.1938 0.4064)
			(stroke
				(width 0.1)
				(type default)
			)
			(layer "F.Fab")
		)
		(fp_line
			(start 0.8636 0.4064)
			(end 0.8636 0.4572)
			(stroke
				(width 0.1)
				(type default)
			)
			(layer "F.Fab")
		)
		(fp_line
			(start 1.1938 0.4064)
			(end 0.8636 0.4064)
			(stroke
				(width 0.1)
				(type default)
			)
			(layer "F.Fab")
		)
		(fp_line
			(start -1.1938 -0.4064)
			(end -0.8636 -0.4064)
			(stroke
				(width 0.1)
				(type default)
			)
			(layer "F.Fab")
		)
		(fp_line
			(start -0.8636 -0.4064)
			(end -0.8636 -0.4572)
			(stroke
				(width 0.1)
				(type default)
			)
			(layer "F.Fab")
		)
		(fp_line
			(start 0.8636 -0.4064)
			(end 1.1938 -0.4064)
			(stroke
				(width 0.1)
				(type default)
			)
			(layer "F.Fab")
		)
		(fp_line
			(start 1.1938 -0.4064)
			(end 1.1938 0.4064)
			(stroke
				(width 0.1)
				(type default)
			)
			(layer "F.Fab")
		)
		(fp_line
			(start -0.8636 -0.4572)
			(end 0.8636 -0.4572)
			(stroke
				(width 0.1)
				(type default)
			)
			(layer "F.Fab")
		)
		(fp_line
			(start 0.8636 -0.4572)
			(end 0.8636 -0.4064)
			(stroke
				(width 0.1)
				(type default)
			)
			(layer "F.Fab")
		)
		(pad "1" smd rect
			(at -0.7366 0 180)
			(size 0.7112 0.8128)
			(layers "F.Cu" "F.Mask" "F.Paste")
			(net "P12V_HSC_TEMP_D+")
		)
		(pad "2" smd rect
			(at 0.7366 0 180)
			(size 0.7112 0.8128)
			(layers "F.Cu" "F.Mask" "F.Paste")
			(net "P12V_HSC_TEMP_D-")
		)
	)
)
